FILE_TYPE=LIBRARY_PARTS;
primitive 'CONN8_HBB1081L200D8H';
  pin
    '1':
      PIN_NUMBER='(1)';
      BIDIRECTIONAL='TRUE';
      INPUT_LOAD='(-0.01,0.01)';
      OUTPUT_LOAD='(1.0,-1.0)';
    '2':
      PIN_NUMBER='(2)';
      BIDIRECTIONAL='TRUE';
      INPUT_LOAD='(-0.01,0.01)';
      OUTPUT_LOAD='(1.0,-1.0)';
    '3':
      PIN_NUMBER='(3)';
      BIDIRECTIONAL='TRUE';
      INPUT_LOAD='(-0.01,0.01)';
      OUTPUT_LOAD='(1.0,-1.0)';
    '4':
      PIN_NUMBER='(4)';
      BIDIRECTIONAL='TRUE';
      INPUT_LOAD='(-0.01,0.01)';
      OUTPUT_LOAD='(1.0,-1.0)';
    '5':
      PIN_NUMBER='(5)';
      BIDIRECTIONAL='TRUE';
      INPUT_LOAD='(-0.01,0.01)';
      OUTPUT_LOAD='(1.0,-1.0)';
    '6':
      PIN_NUMBER='(6)';
      BIDIRECTIONAL='TRUE';
      INPUT_LOAD='(-0.01,0.01)';
      OUTPUT_LOAD='(1.0,-1.0)';
    '7':
      PIN_NUMBER='(7)';
      BIDIRECTIONAL='TRUE';
      INPUT_LOAD='(-0.01,0.01)';
      OUTPUT_LOAD='(1.0,-1.0)';
    '8':
      PIN_NUMBER='(8)';
      BIDIRECTIONAL='TRUE';
      INPUT_LOAD='(-0.01,0.01)';
      OUTPUT_LOAD='(1.0,-1.0)';
  end_pin;
  body
    PART_NAME='CONN8_HBB1081L200D8H';
    BODY_NAME='CONN8_HBB1081L200D8H';
    PHYS_DES_PREFIX='J';
    CLASS='IO';
  end_body;
end_primitive;

END.
